1 2 3 4 5 6 7 8 9 10 11 12 13 14
1413121110987654321
DRAWING NO.
SCALE DWG
DO NOT 
MODEL NAME
APPD
CKD
DSN
DRN
SHEET
SIGNDESCRIPTION DATE
Wiwynn Corporation
A
B
C
D
E
G
F
H
I
J
A
B
C
D
E
F
G
H
I
J
MATERIAL
FINISH
OF
DIM IN  mm
REV
34.86
0.00
41.85
2-14.70
2.41
(PTH)2.55
 (NO TRACE AT ALL LAYERS EXCEPT GND)5.00
 (PTH)2.20
 (PTH)2.20
 (NO TRACE AT ALL LAYERS EXCEPT GND)5.00
(NO TRACE AT ALL LAYERS EXCEPT GND)5.00
110.05
0.00
25.00
10.00
105.05
60.55
40.05
120.00
4-188.00
15.00
(PTH)4.00
 (PTH)4.00
9-  (PTH)3.50
(PTH)4.20
(NPTH)3.00
(NPTH)3.00
(NO TRACE AT ALL LAYERS)6.00
(NO TRACE AT ALL LAYERS)6.00
18.00
0.00
30.53
73.03
12.50
92.50
155.50
222.50
124.17
0.00
160.00
180.00
103.00
222.50
219.80
165.80
155.50
80.00
18.00
194.00
120.00
110.00 110.00
84.48
170.00
41.45
222.50
(NO TRACE AT ALL LAYERS EXCEPT GND)7.50
(PAD)(NO TRACE AT ALL LAYERS)9.50
235.00
22.80
78.50
45.72
3.40
6.80
(NPTH)3.40
(NPTH)3.30
(NPTH)3.30
22.90
78.55
105.05
(PAD)(NO TRACE AT ALL LAYERS)9.50
9- (PAD)(NO TRACE AT ALL LAYERS)9.50
103.70
144.30
48.00
9- (PAD)(NO TRACE AT ALL LAYERS)9.50(PAD)(NO TRACE AT ALL LAYERS)9.50
(PAD)(NO TRACE AT ALL LAYERS)9.50
BryceCanyon
CD 
Jess Wang 7/31
2017
Jess Wang 7/31
2017
Bryce Canyon IO Module (w/ IOC)
TU863+VLP / NPG171+VLP T=1.6mm 
1 1 Lenny Kao
Lenny Kao 
7/31
2017
7/31
2017
SEE DETAIL A
COMPONENT SIDE
SOLDER SIDE
SMT NUT(087_71242_0465)
SEE DETAIL  A
9-PAD(ZZ_AFEN8_138)
16318-2 VERSION A 2017-07-31
DETAIL  A
SCALE  3.000